(kicad_pcb
	(version 20260206)
	(generator "pcbnew")
	(generator_version "10.0")
	(general
		(thickness 1.6)
		(legacy_teardrops no)
	)
	(paper "A4")
	(title_block
		(title "03242023_DA0F0TMBIJ0_F0T_Motherboard_J_brd_V01_OCP.brd")
		(comment 1 "Grand Teton / footprints 3288-3293 of 6105")
	)
	(layers
		(0 "F.Cu" signal "TOP")
		(4 "In1.Cu" signal "GND")
		(6 "In2.Cu" signal "IN1")
		(8 "In3.Cu" signal "GND1")
		(10 "In4.Cu" signal "IN2")
		(12 "In5.Cu" signal "GND2")
		(14 "In6.Cu" signal "IN3")
		(16 "In7.Cu" signal "GND3")
		(18 "In8.Cu" signal "VCC")
		(20 "In9.Cu" signal "VCC1")
		(22 "In10.Cu" signal "GND4")
		(24 "In11.Cu" signal "IN4")
		(26 "In12.Cu" signal "GND5")
		(28 "In13.Cu" signal "IN5")
		(30 "In14.Cu" signal "GND6")
		(32 "In15.Cu" signal "IN6")
		(34 "In16.Cu" signal "GND7")
		(2 "B.Cu" signal "BOTTOM")
		(9 "F.Adhes" user "F.Adhesive")
		(11 "B.Adhes" user "B.Adhesive")
		(13 "F.Paste" user "Package Geometry/Pastemask Top")
		(15 "B.Paste" user "Package Geometry/Pastemask Bottom")
		(5 "F.SilkS" user "Ref Des/Silkscreen Top")
		(7 "B.SilkS" user "Ref Des/Silkscreen Bottom")
		(1 "F.Mask" user "Board Geometry/Soldermask Top")
		(3 "B.Mask" user "Board Geometry/Soldermask Bottom")
		(17 "Dwgs.User" user "User.Drawings")
		(19 "Cmts.User" user "User.Comments")
		(21 "Eco1.User" user "User.Eco1")
		(23 "Eco2.User" user "User.Eco2")
		(25 "Edge.Cuts" user "Board Geometry/Outline")
		(27 "Margin" user)
		(31 "F.CrtYd" user "Package Geometry/Place Bound Top")
		(29 "B.CrtYd" user "Package Geometry/Place Bound Bottom")
		(35 "F.Fab" user "Ref Des/Assembly Top")
		(33 "B.Fab" user "Ref Des/Assembly Bottom")
	)
	(footprint ""
		(layer "F.Cu")
		(at 148.98243 -77.229208)
		(property "Reference" "R3131"
			(at 0 0 0)
			(layer "F.SilkS")
			(hide yes)
			(effects
				(font
					(size 1.27 1.27)
				)
			)
		)
		(property "Value" ""
			(at 0 0 0)
			(layer "F.Fab")
			(effects
				(font
					(size 1.27 1.27)
				)
			)
		)
		(duplicate_pad_numbers_are_jumpers no)
		(fp_line
			(start -0.7874 -0.4064)
			(end 0.7874 -0.4064)
			(stroke
				(width 0.1524)
				(type default)
			)
			(layer "F.SilkS")
		)
		(fp_line
			(start -0.7874 0.4064)
			(end -0.7874 -0.4064)
			(stroke
				(width 0.1524)
				(type default)
			)
			(layer "F.SilkS")
		)
		(fp_line
			(start 0.7874 -0.4064)
			(end 0.7874 0.4064)
			(stroke
				(width 0.1524)
				(type default)
			)
			(layer "F.SilkS")
		)
		(fp_line
			(start 0.7874 0.4064)
			(end -0.7874 0.4064)
			(stroke
				(width 0.1524)
				(type default)
			)
			(layer "F.SilkS")
		)
		(fp_line
			(start -0.67945 -0.305054)
			(end -0.12065 -0.305054)
			(stroke
				(width 0.1)
				(type default)
			)
			(layer "F.Fab")
		)
		(fp_line
			(start -0.67945 0.3048)
			(end -0.67945 -0.305054)
			(stroke
				(width 0.1)
				(type default)
			)
			(layer "F.Fab")
		)
		(fp_line
			(start -0.12065 -0.305054)
			(end -0.12065 -0.2794)
			(stroke
				(width 0.1)
				(type default)
			)
			(layer "F.Fab")
		)
		(fp_line
			(start -0.12065 -0.2794)
			(end 0.12065 -0.2794)
			(stroke
				(width 0.1)
				(type default)
			)
			(layer "F.Fab")
		)
		(fp_line
			(start -0.12065 0.2794)
			(end -0.12065 0.3048)
			(stroke
				(width 0.1)
				(type default)
			)
			(layer "F.Fab")
		)
		(fp_line
			(start -0.12065 0.3048)
			(end -0.67945 0.3048)
			(stroke
				(width 0.1)
				(type default)
			)
			(layer "F.Fab")
		)
		(fp_line
			(start 0.120396 0.2794)
			(end -0.12065 0.2794)
			(stroke
				(width 0.1)
				(type default)
			)
			(layer "F.Fab")
		)
		(fp_line
			(start 0.120396 0.3048)
			(end 0.120396 0.2794)
			(stroke
				(width 0.1)
				(type default)
			)
			(layer "F.Fab")
		)
		(fp_line
			(start 0.12065 -0.3048)
			(end 0.67945 -0.3048)
			(stroke
				(width 0.1)
				(type default)
			)
			(layer "F.Fab")
		)
		(fp_line
			(start 0.12065 -0.2794)
			(end 0.12065 -0.3048)
			(stroke
				(width 0.1)
				(type default)
			)
			(layer "F.Fab")
		)
		(fp_line
			(start 0.67945 -0.3048)
			(end 0.67945 0.3048)
			(stroke
				(width 0.1)
				(type default)
			)
			(layer "F.Fab")
		)
		(fp_line
			(start 0.67945 0.3048)
			(end 0.120396 0.3048)
			(stroke
				(width 0.1)
				(type default)
			)
			(layer "F.Fab")
		)
		(pad "1" smd circle
			(at -0.40005 0)
			(size 0 0)
			(layers "F.Cu" "F.Mask" "F.Paste")
			(net "P3V3_AUX")
		)
		(pad "2" smd circle
			(at 0.40005 0)
			(size 0 0)
			(layers "F.Cu" "F.Mask" "F.Paste")
			(net "PCA9543_S3M_INT3_N")
		)
	)
	(footprint ""
		(layer "F.Cu")
		(at 437.242966 -123.664726 180)
		(property "Reference" "R2399"
			(at 0 0 180)
			(layer "F.SilkS")
			(hide yes)
			(effects
				(font
					(size 1.27 1.27)
				)
			)
		)
		(property "Value" ""
			(at 0 0 180)
			(layer "F.Fab")
			(effects
				(font
					(size 1.27 1.27)
				)
			)
		)
		(duplicate_pad_numbers_are_jumpers no)
		(fp_line
			(start 0.7874 0.4064)
			(end -0.7874 0.4064)
			(stroke
				(width 0.1524)
				(type default)
			)
			(layer "F.SilkS")
		)
		(fp_line
			(start 0.7874 -0.4064)
			(end 0.7874 0.4064)
			(stroke
				(width 0.1524)
				(type default)
			)
			(layer "F.SilkS")
		)
		(fp_line
			(start -0.7874 0.4064)
			(end -0.7874 -0.4064)
			(stroke
				(width 0.1524)
				(type default)
			)
			(layer "F.SilkS")
		)
		(fp_line
			(start -0.7874 -0.4064)
			(end 0.7874 -0.4064)
			(stroke
				(width 0.1524)
				(type default)
			)
			(layer "F.SilkS")
		)
		(fp_line
			(start 0.67945 0.3048)
			(end 0.120396 0.3048)
			(stroke
				(width 0.1)
				(type default)
			)
			(layer "F.Fab")
		)
		(fp_line
			(start 0.67945 -0.3048)
			(end 0.67945 0.3048)
			(stroke
				(width 0.1)
				(type default)
			)
			(layer "F.Fab")
		)
		(fp_line
			(start 0.12065 -0.2794)
			(end 0.12065 -0.3048)
			(stroke
				(width 0.1)
				(type default)
			)
			(layer "F.Fab")
		)
		(fp_line
			(start 0.12065 -0.3048)
			(end 0.67945 -0.3048)
			(stroke
				(width 0.1)
				(type default)
			)
			(layer "F.Fab")
		)
		(fp_line
			(start 0.120396 0.3048)
			(end 0.120396 0.2794)
			(stroke
				(width 0.1)
				(type default)
			)
			(layer "F.Fab")
		)
		(fp_line
			(start 0.120396 0.2794)
			(end -0.12065 0.2794)
			(stroke
				(width 0.1)
				(type default)
			)
			(layer "F.Fab")
		)
		(fp_line
			(start -0.12065 0.3048)
			(end -0.67945 0.3048)
			(stroke
				(width 0.1)
				(type default)
			)
			(layer "F.Fab")
		)
		(fp_line
			(start -0.12065 0.2794)
			(end -0.12065 0.3048)
			(stroke
				(width 0.1)
				(type default)
			)
			(layer "F.Fab")
		)
		(fp_line
			(start -0.12065 -0.2794)
			(end 0.12065 -0.2794)
			(stroke
				(width 0.1)
				(type default)
			)
			(layer "F.Fab")
		)
		(fp_line
			(start -0.12065 -0.305054)
			(end -0.12065 -0.2794)
			(stroke
				(width 0.1)
				(type default)
			)
			(layer "F.Fab")
		)
		(fp_line
			(start -0.67945 0.3048)
			(end -0.67945 -0.305054)
			(stroke
				(width 0.1)
				(type default)
			)
			(layer "F.Fab")
		)
		(fp_line
			(start -0.67945 -0.305054)
			(end -0.12065 -0.305054)
			(stroke
				(width 0.1)
				(type default)
			)
			(layer "F.Fab")
		)
		(pad "1" smd circle
			(at -0.40005 0 180)
			(size 0 0)
			(layers "F.Cu" "F.Mask" "F.Paste")
			(net "SVID_CLK1_CPU0_R")
		)
		(pad "2" smd circle
			(at 0.40005 0 180)
			(size 0 0)
			(layers "F.Cu" "F.Mask" "F.Paste")
			(net "SVID_CLK_PVCCD_HV_CPU0_R")
		)
	)
	(footprint ""
		(layer "F.Cu")
		(at 354.251514 -255.053846 90)
		(property "Reference" "C990"
			(at 0 0 90)
			(layer "F.SilkS")
			(hide yes)
			(effects
				(font
					(size 1.27 1.27)
				)
			)
		)
		(property "Value" ""
			(at 0 0 90)
			(layer "F.Fab")
			(effects
				(font
					(size 1.27 1.27)
				)
			)
		)
		(duplicate_pad_numbers_are_jumpers no)
		(fp_line
			(start 0.7874 -0.4064)
			(end 0.7874 0.4064)
			(stroke
				(width 0.1524)
				(type default)
			)
			(layer "F.SilkS")
		)
		(fp_line
			(start -0.7874 -0.4064)
			(end 0.7874 -0.4064)
			(stroke
				(width 0.1524)
				(type default)
			)
			(layer "F.SilkS")
		)
		(fp_line
			(start 0.7874 0.4064)
			(end -0.7874 0.4064)
			(stroke
				(width 0.1524)
				(type default)
			)
			(layer "F.SilkS")
		)
		(fp_line
			(start -0.7874 0.4064)
			(end -0.7874 -0.4064)
			(stroke
				(width 0.1524)
				(type default)
			)
			(layer "F.SilkS")
		)
		(fp_line
			(start -0.12065 -0.305054)
			(end -0.12065 -0.2794)
			(stroke
				(width 0.1)
				(type default)
			)
			(layer "F.Fab")
		)
		(fp_line
			(start -0.67945 -0.305054)
			(end -0.12065 -0.305054)
			(stroke
				(width 0.1)
				(type default)
			)
			(layer "F.Fab")
		)
		(fp_line
			(start 0.67945 -0.3048)
			(end 0.67945 0.3048)
			(stroke
				(width 0.1)
				(type default)
			)
			(layer "F.Fab")
		)
		(fp_line
			(start 0.12065 -0.3048)
			(end 0.67945 -0.3048)
			(stroke
				(width 0.1)
				(type default)
			)
			(layer "F.Fab")
		)
		(fp_line
			(start 0.12065 -0.2794)
			(end 0.12065 -0.3048)
			(stroke
				(width 0.1)
				(type default)
			)
			(layer "F.Fab")
		)
		(fp_line
			(start -0.12065 -0.2794)
			(end 0.12065 -0.2794)
			(stroke
				(width 0.1)
				(type default)
			)
			(layer "F.Fab")
		)
		(fp_line
			(start 0.120396 0.2794)
			(end -0.12065 0.2794)
			(stroke
				(width 0.1)
				(type default)
			)
			(layer "F.Fab")
		)
		(fp_line
			(start -0.12065 0.2794)
			(end -0.12065 0.3048)
			(stroke
				(width 0.1)
				(type default)
			)
			(layer "F.Fab")
		)
		(fp_line
			(start 0.67945 0.3048)
			(end 0.120396 0.3048)
			(stroke
				(width 0.1)
				(type default)
			)
			(layer "F.Fab")
		)
		(fp_line
			(start 0.120396 0.3048)
			(end 0.120396 0.2794)
			(stroke
				(width 0.1)
				(type default)
			)
			(layer "F.Fab")
		)
		(fp_line
			(start -0.12065 0.3048)
			(end -0.67945 0.3048)
			(stroke
				(width 0.1)
				(type default)
			)
			(layer "F.Fab")
		)
		(fp_line
			(start -0.67945 0.3048)
			(end -0.67945 -0.305054)
			(stroke
				(width 0.1)
				(type default)
			)
			(layer "F.Fab")
		)
		(pad "1" smd circle
			(at -0.40005 0 90)
			(size 0 0)
			(layers "F.Cu" "F.Mask" "F.Paste")
			(net "PVCCIN_CPU0")
		)
		(pad "2" smd circle
			(at 0.40005 0 90)
			(size 0 0)
			(layers "F.Cu" "F.Mask" "F.Paste")
			(net "GND")
		)
	)
	(footprint ""
		(layer "F.Cu")
		(at 116.561616 -238.162592 90)
		(property "Reference" "C434"
			(at 0 0 90)
			(layer "F.SilkS")
			(hide yes)
			(effects
				(font
					(size 1.27 1.27)
				)
			)
		)
		(property "Value" ""
			(at 0 0 90)
			(layer "F.Fab")
			(effects
				(font
					(size 1.27 1.27)
				)
			)
		)
		(duplicate_pad_numbers_are_jumpers no)
		(fp_line
			(start 0.7874 -0.4064)
			(end 0.7874 0.4064)
			(stroke
				(width 0.1524)
				(type default)
			)
			(layer "F.SilkS")
		)
		(fp_line
			(start -0.7874 -0.4064)
			(end 0.7874 -0.4064)
			(stroke
				(width 0.1524)
				(type default)
			)
			(layer "F.SilkS")
		)
		(fp_line
			(start 0.7874 0.4064)
			(end -0.7874 0.4064)
			(stroke
				(width 0.1524)
				(type default)
			)
			(layer "F.SilkS")
		)
		(fp_line
			(start -0.7874 0.4064)
			(end -0.7874 -0.4064)
			(stroke
				(width 0.1524)
				(type default)
			)
			(layer "F.SilkS")
		)
		(fp_line
			(start -0.12065 -0.305054)
			(end -0.12065 -0.2794)
			(stroke
				(width 0.1)
				(type default)
			)
			(layer "F.Fab")
		)
		(fp_line
			(start -0.67945 -0.305054)
			(end -0.12065 -0.305054)
			(stroke
				(width 0.1)
				(type default)
			)
			(layer "F.Fab")
		)
		(fp_line
			(start 0.67945 -0.3048)
			(end 0.67945 0.3048)
			(stroke
				(width 0.1)
				(type default)
			)
			(layer "F.Fab")
		)
		(fp_line
			(start 0.12065 -0.3048)
			(end 0.67945 -0.3048)
			(stroke
				(width 0.1)
				(type default)
			)
			(layer "F.Fab")
		)
		(fp_line
			(start 0.12065 -0.2794)
			(end 0.12065 -0.3048)
			(stroke
				(width 0.1)
				(type default)
			)
			(layer "F.Fab")
		)
		(fp_line
			(start -0.12065 -0.2794)
			(end 0.12065 -0.2794)
			(stroke
				(width 0.1)
				(type default)
			)
			(layer "F.Fab")
		)
		(fp_line
			(start 0.120396 0.2794)
			(end -0.12065 0.2794)
			(stroke
				(width 0.1)
				(type default)
			)
			(layer "F.Fab")
		)
		(fp_line
			(start -0.12065 0.2794)
			(end -0.12065 0.3048)
			(stroke
				(width 0.1)
				(type default)
			)
			(layer "F.Fab")
		)
		(fp_line
			(start 0.67945 0.3048)
			(end 0.120396 0.3048)
			(stroke
				(width 0.1)
				(type default)
			)
			(layer "F.Fab")
		)
		(fp_line
			(start 0.120396 0.3048)
			(end 0.120396 0.2794)
			(stroke
				(width 0.1)
				(type default)
			)
			(layer "F.Fab")
		)
		(fp_line
			(start -0.12065 0.3048)
			(end -0.67945 0.3048)
			(stroke
				(width 0.1)
				(type default)
			)
			(layer "F.Fab")
		)
		(fp_line
			(start -0.67945 0.3048)
			(end -0.67945 -0.305054)
			(stroke
				(width 0.1)
				(type default)
			)
			(layer "F.Fab")
		)
		(pad "1" smd circle
			(at -0.40005 0 90)
			(size 0 0)
			(layers "F.Cu" "F.Mask" "F.Paste")
			(net "PVCCINFAON_CPU1")
		)
		(pad "2" smd circle
			(at 0.40005 0 90)
			(size 0 0)
			(layers "F.Cu" "F.Mask" "F.Paste")
			(net "GND")
		)
	)
	(footprint ""
		(layer "F.Cu")
		(at 194.35064 -69.423788 -90)
		(property "Reference" "PU293"
			(at 3.817112 3.85572 0)
			(unlocked yes)
			(layer "F.SilkS")
			(effects
				(font
					(size 0.7874 0.5842)
					(thickness 0.1524)
				)
			)
		)
		(property "Value" ""
			(at 0 0 270)
			(layer "F.Fab")
			(effects
				(font
					(size 1.27 1.27)
				)
			)
		)
		(duplicate_pad_numbers_are_jumpers no)
		(fp_line
			(start -1.239774 1.495298)
			(end -1.239774 -1.495298)
			(stroke
				(width 0.1524)
				(type default)
			)
			(layer "F.SilkS")
		)
		(fp_line
			(start 1.239774 1.495298)
			(end -1.239774 1.495298)
			(stroke
				(width 0.1524)
				(type default)
			)
			(layer "F.SilkS")
		)
		(fp_line
			(start -1.239774 -1.495298)
			(end 1.239774 -1.495298)
			(stroke
				(width 0.1524)
				(type default)
			)
			(layer "F.SilkS")
		)
		(fp_line
			(start 1.239774 -1.495298)
			(end 1.239774 1.495298)
			(stroke
				(width 0.1524)
				(type default)
			)
			(layer "F.SilkS")
		)
		(fp_poly
			(pts
				(xy -1.754124 -1.697228) (xy -1.394968 -0.619506) (xy -2.472436 -0.978662)
			)
			(stroke
				(width 0)
				(type default)
			)
			(fill yes)
			(layer "F.SilkS")
		)
		(fp_line
			(start -0.8001 1.050036)
			(end -0.8001 -1.050036)
			(stroke
				(width 0.1)
				(type default)
			)
			(layer "F.Fab")
		)
		(fp_line
			(start 0.8001 1.050036)
			(end -0.8001 1.050036)
			(stroke
				(width 0.1)
				(type default)
			)
			(layer "F.Fab")
		)
		(fp_line
			(start -0.8001 -1.050036)
			(end 0.8001 -1.050036)
			(stroke
				(width 0.1)
				(type default)
			)
			(layer "F.Fab")
		)
		(fp_line
			(start 0.8001 -1.050036)
			(end 0.8001 1.050036)
			(stroke
				(width 0.1)
				(type default)
			)
			(layer "F.Fab")
		)
		(fp_poly
			(pts
				(xy -2.458974 -0.508) (xy -2.458974 0.508) (xy -1.442974 0)
			)
			(stroke
				(width 0)
				(type default)
			)
			(fill yes)
			(layer "F.Fab")
		)
		(pad "1_2" smd circle
			(at -0.374904 0)
			(size 0 0)
			(layers "F.Cu" "F.Mask" "F.Paste")
			(net "P3V3_AUX")
		)
		(pad "3" smd rect
			(at -0.499872 0.999998 270)
			(size 0.254 0.7112)
			(layers "F.Cu" "F.Mask" "F.Paste")
			(net "GND")
		)
		(pad "4" smd rect
			(at 0 0.999998 270)
			(size 0.254 0.7112)
			(layers "F.Cu" "F.Mask" "F.Paste")
			(net "P3V3_E1S_ILIMIT_0")
		)
		(pad "5" smd rect
			(at 0.499872 0.999998 270)
			(size 0.254 0.7112)
			(layers "F.Cu" "F.Mask" "F.Paste")
			(net "P3V3_E1S_MODE_0")
		)
		(pad "6_7" smd circle
			(at 0.374904 0 180)
			(size 0 0)
			(layers "F.Cu" "F.Mask" "F.Paste")
			(net "P3V3_E1S_0_R")
		)
		(pad "8" smd rect
			(at 0.499872 -0.999998 270)
			(size 0.254 0.7112)
			(layers "F.Cu" "F.Mask" "F.Paste")
			(net "P3V3_E1S_GATE_0_PU293")
		)
		(pad "9" smd rect
			(at 0 -0.999998 270)
			(size 0.254 0.7112)
			(layers "F.Cu" "F.Mask" "F.Paste")
			(net "P3V3_E1S_EN_0_R2")
		)
		(pad "10" smd rect
			(at -0.499872 -0.999998 270)
			(size 0.254 0.7112)
			(layers "F.Cu" "F.Mask" "F.Paste")
			(net "P3V3_E1S_DVDT_0")
		)
	)
	(footprint ""
		(layer "F.Cu")
		(at 345.27871 -343.902284 90)
		(property "Reference" "PC318"
			(at 0 0 90)
			(layer "F.SilkS")
			(hide yes)
			(effects
				(font
					(size 1.27 1.27)
				)
			)
		)
		(property "Value" ""
			(at 0 0 90)
			(layer "F.Fab")
			(effects
				(font
					(size 1.27 1.27)
				)
			)
		)
		(duplicate_pad_numbers_are_jumpers no)
		(fp_line
			(start -3.400044 1.249934)
			(end 3.400044 1.249934)
			(stroke
				(width 0.1524)
				(type default)
			)
			(layer "F.SilkS")
		)
		(fp_circle
			(center 0 1.249934)
			(end 0 4.649978)
			(stroke
				(width 0.1524)
				(type default)
			)
			(fill no)
			(layer "F.SilkS")
		)
		(fp_poly
			(pts
				(arc
					(start -3.400044 1.249934)
					(mid 0 4.649978)
					(end 3.400044 1.249934)
				)
			)
			(stroke
				(width 0)
				(type default)
			)
			(fill yes)
			(layer "F.SilkS")
		)
		(fp_circle
			(center 0 1.249934)
			(end 0 4.649978)
			(stroke
				(width 0.1)
				(type default)
			)
			(fill no)
			(layer "F.Fab")
		)
		(pad "1" thru_hole rect
			(at 0 0 90)
			(size 1.524 1.524)
			(drill 1.016)
			(layers "*.Cu" "*.Mask")
			(remove_unused_layers no)
			(net "SW_P12V_PVCCIN_CPU0_FLT")
			(clearance 0)
			(padstack
				(mode front_inner_back)
				(layer "Inner"
					(shape circle)
					(size 1.524 1.524)
					(clearance 0)
				)
				(layer "B.Cu"
					(shape rect)
					(size 1.524 1.524)
					(clearance 0)
				)
			)
		)
		(pad "2" thru_hole circle
			(at 0 2.500122 90)
			(size 1.524 1.524)
			(drill 1.016)
			(layers "*.Cu" "*.Mask")
			(remove_unused_layers no)
			(net "GND")
			(clearance 0)
		)
	)
)
